# S9S_MB_2U (Grand Teton) — schematic netlist excerpt (pin names and nets, part order shuffled) for the footprints in the layout excerpt that follows; sources: Cadence DE-HDL packaged netlist, KiCad conversion of 03242023_DA0F0TMBIJ0_F0T_Motherboard_J_brd_V01_OCP.brd

PD103  SCHOTTKY_AC  B340A-13-F IC  pkg D2010XF  page 156 : A = GND ; C = P3V3_OCP_SFF_R
R3273  Q_RES  68K 1% EMPTY  pkg 0402LF  page 166 : A = FM_P2E_FGA ; B = GND

(kicad_pcb
	(version 20260206)
	(generator "pcbnew")
	(generator_version "10.0")
	(general
		(thickness 1.6)
		(legacy_teardrops no)
	)
	(paper "A4")
	(title_block
		(title "03242023_DA0F0TMBIJ0_F0T_Motherboard_J_brd_V01_OCP.brd")
		(comment 1 "Grand Teton / footprints 1262-1263 of 6105")
	)
	(layers
		(0 "F.Cu" signal "TOP")
		(4 "In1.Cu" signal "GND")
		(6 "In2.Cu" signal "IN1")
		(8 "In3.Cu" signal "GND1")
		(10 "In4.Cu" signal "IN2")
		(12 "In5.Cu" signal "GND2")
		(14 "In6.Cu" signal "IN3")
		(16 "In7.Cu" signal "GND3")
		(18 "In8.Cu" signal "VCC")
		(20 "In9.Cu" signal "VCC1")
		(22 "In10.Cu" signal "GND4")
		(24 "In11.Cu" signal "IN4")
		(26 "In12.Cu" signal "GND5")
		(28 "In13.Cu" signal "IN5")
		(30 "In14.Cu" signal "GND6")
		(32 "In15.Cu" signal "IN6")
		(34 "In16.Cu" signal "GND7")
		(2 "B.Cu" signal "BOTTOM")
		(9 "F.Adhes" user "F.Adhesive")
		(11 "B.Adhes" user "B.Adhesive")
		(13 "F.Paste" user "Package Geometry/Pastemask Top")
		(15 "B.Paste" user "Package Geometry/Pastemask Bottom")
		(5 "F.SilkS" user "Ref Des/Silkscreen Top")
		(7 "B.SilkS" user "Ref Des/Silkscreen Bottom")
		(1 "F.Mask" user "Board Geometry/Soldermask Top")
		(3 "B.Mask" user "Board Geometry/Soldermask Bottom")
		(17 "Dwgs.User" user "User.Drawings")
		(19 "Cmts.User" user "User.Comments")
		(21 "Eco1.User" user "User.Eco1")
		(23 "Eco2.User" user "User.Eco2")
		(25 "Edge.Cuts" user "Board Geometry/Outline")
		(27 "Margin" user)
		(31 "F.CrtYd" user "Package Geometry/Place Bound Top")
		(29 "B.CrtYd" user "Package Geometry/Place Bound Bottom")
		(35 "F.Fab" user "Ref Des/Assembly Top")
		(33 "B.Fab" user "Ref Des/Assembly Bottom")
	)
	(footprint ""
		(layer "F.Cu")
		(at 15.436596 -392.199876 180)
		(property "Reference" "R3273"
			(at 0 0 180)
			(layer "F.SilkS")
			(hide yes)
			(effects
				(font
					(size 1.27 1.27)
				)
			)
		)
		(property "Value" ""
			(at 0 0 180)
			(layer "F.Fab")
			(effects
				(font
					(size 1.27 1.27)
				)
			)
		)
		(duplicate_pad_numbers_are_jumpers no)
		(fp_line
			(start 0.7874 0.4064)
			(end -0.7874 0.4064)
			(stroke
				(width 0.1524)
				(type default)
			)
			(layer "F.SilkS")
		)
		(fp_line
			(start 0.7874 -0.4064)
			(end 0.7874 0.4064)
			(stroke
				(width 0.1524)
				(type default)
			)
			(layer "F.SilkS")
		)
		(fp_line
			(start -0.7874 0.4064)
			(end -0.7874 -0.4064)
			(stroke
				(width 0.1524)
				(type default)
			)
			(layer "F.SilkS")
		)
		(fp_line
			(start -0.7874 -0.4064)
			(end 0.7874 -0.4064)
			(stroke
				(width 0.1524)
				(type default)
			)
			(layer "F.SilkS")
		)
		(fp_line
			(start 0.67945 0.3048)
			(end 0.120396 0.3048)
			(stroke
				(width 0.1)
				(type default)
			)
			(layer "F.Fab")
		)
		(fp_line
			(start 0.67945 -0.3048)
			(end 0.67945 0.3048)
			(stroke
				(width 0.1)
				(type default)
			)
			(layer "F.Fab")
		)
		(fp_line
			(start 0.12065 -0.2794)
			(end 0.12065 -0.3048)
			(stroke
				(width 0.1)
				(type default)
			)
			(layer "F.Fab")
		)
		(fp_line
			(start 0.12065 -0.3048)
			(end 0.67945 -0.3048)
			(stroke
				(width 0.1)
				(type default)
			)
			(layer "F.Fab")
		)
		(fp_line
			(start 0.120396 0.3048)
			(end 0.120396 0.2794)
			(stroke
				(width 0.1)
				(type default)
			)
			(layer "F.Fab")
		)
		(fp_line
			(start 0.120396 0.2794)
			(end -0.12065 0.2794)
			(stroke
				(width 0.1)
				(type default)
			)
			(layer "F.Fab")
		)
		(fp_line
			(start -0.12065 0.3048)
			(end -0.67945 0.3048)
			(stroke
				(width 0.1)
				(type default)
			)
			(layer "F.Fab")
		)
		(fp_line
			(start -0.12065 0.2794)
			(end -0.12065 0.3048)
			(stroke
				(width 0.1)
				(type default)
			)
			(layer "F.Fab")
		)
		(fp_line
			(start -0.12065 -0.2794)
			(end 0.12065 -0.2794)
			(stroke
				(width 0.1)
				(type default)
			)
			(layer "F.Fab")
		)
		(fp_line
			(start -0.12065 -0.305054)
			(end -0.12065 -0.2794)
			(stroke
				(width 0.1)
				(type default)
			)
			(layer "F.Fab")
		)
		(fp_line
			(start -0.67945 0.3048)
			(end -0.67945 -0.305054)
			(stroke
				(width 0.1)
				(type default)
			)
			(layer "F.Fab")
		)
		(fp_line
			(start -0.67945 -0.305054)
			(end -0.12065 -0.305054)
			(stroke
				(width 0.1)
				(type default)
			)
			(layer "F.Fab")
		)
		(pad "1" smd circle
			(at -0.40005 0 180)
			(size 0 0)
			(layers "F.Cu" "F.Mask" "F.Paste")
			(net "FM_P2E_FGA")
		)
		(pad "2" smd circle
			(at 0.40005 0 180)
			(size 0 0)
			(layers "F.Cu" "F.Mask" "F.Paste")
			(net "GND")
		)
	)
	(footprint ""
		(layer "F.Cu")
		(at 422.623742 -97.941892)
		(property "Reference" "PD103"
			(at -3.13182 2.806192 0)
			(unlocked yes)
			(layer "F.SilkS")
			(effects
				(font
					(size 0.7874 0.5842)
					(thickness 0.1524)
				)
				(justify left)
			)
		)
		(property "Value" ""
			(at 0 0 0)
			(layer "F.Fab")
			(effects
				(font
					(size 1.27 1.27)
				)
			)
		)
		(duplicate_pad_numbers_are_jumpers no)
		(fp_line
			(start -3.400044 -1.459992)
			(end 4.107942 -1.459992)
			(stroke
				(width 0.1524)
				(type default)
			)
			(layer "F.SilkS")
		)
		(fp_line
			(start -3.400044 1.459992)
			(end -3.400044 -1.459992)
			(stroke
				(width 0.1524)
				(type default)
			)
			(layer "F.SilkS")
		)
		(fp_line
			(start 4.107942 -1.459992)
			(end 4.107942 1.459992)
			(stroke
				(width 0.1524)
				(type default)
			)
			(layer "F.SilkS")
		)
		(fp_line
			(start 4.107942 1.459992)
			(end -3.400044 1.459992)
			(stroke
				(width 0.1524)
				(type default)
			)
			(layer "F.SilkS")
		)
		(fp_rect
			(start 3.308096 1.459992)
			(end 4.107942 -1.459992)
			(stroke
				(width 0)
				(type default)
			)
			(fill yes)
			(layer "F.SilkS")
		)
		(fp_line
			(start -2.29997 -1.459992)
			(end 2.29997 -1.459992)
			(stroke
				(width 0.1)
				(type default)
			)
			(layer "F.Fab")
		)
		(fp_line
			(start -2.29997 1.459992)
			(end -2.29997 -1.459992)
			(stroke
				(width 0.1)
				(type default)
			)
			(layer "F.Fab")
		)
		(fp_line
			(start 2.29997 -1.459992)
			(end 2.29997 1.459992)
			(stroke
				(width 0.1)
				(type default)
			)
			(layer "F.Fab")
		)
		(fp_line
			(start 2.29997 1.459992)
			(end -2.29997 1.459992)
			(stroke
				(width 0.1)
				(type default)
			)
			(layer "F.Fab")
		)
		(fp_text user "+"
			(at -4.7752 -0.12065 0)
			(unlocked yes)
			(layer "F.SilkS")
			(effects
				(font
					(size 1.905 1.4224)
					(thickness 0.1524)
				)
				(justify left)
			)
		)
		(fp_text user "-"
			(at 3.8735 2.64795 180)
			(unlocked yes)
			(layer "F.SilkS")
			(effects
				(font
					(size 1.905 1.4224)
					(thickness 0.1524)
				)
				(justify left)
			)
		)
		(fp_text user "+"
			(at -4.7752 -0.12065 0)
			(unlocked yes)
			(layer "F.Fab")
			(effects
				(font
					(size 1.905 1.4224)
					(thickness 0.1524)
				)
				(justify left)
			)
		)
		(fp_text user "-"
			(at 5.4102 0.29845 180)
			(unlocked yes)
			(layer "F.Fab")
			(effects
				(font
					(size 1.905 1.4224)
					(thickness 0.1524)
				)
				(justify left)
			)
		)
		(pad "A" smd rect
			(at -1.999996 0 90)
			(size 1.7018 2.5146)
			(layers "F.Cu" "F.Mask" "F.Paste")
			(net "GND")
		)
		(pad "C" smd rect
			(at 1.999996 0 90)
			(size 1.7018 2.5146)
			(layers "F.Cu" "F.Mask" "F.Paste")
			(net "P3V3_OCP_SFF_R")
		)
	)
)
